FILE_TYPE=LIBRARY_PARTS;
primitive 'ISL28022FRZT';
  pin
    'VCC':
      PIN_NUMBER='(9)';
      PINUSE='POWER';
      NO_LOAD_CHECK='Both';
      NO_IO_CHECK='Both';
      NO_ASSERT_CHECK='TRUE';
      NO_DIR_CHECK='TRUE';
      ALLOW_CONNECT='TRUE';
    'A1':
      PIN_NUMBER='(1)';
      INPUT_LOAD='(-0.01,0.01)';
    'A0':
      PIN_NUMBER='(2)';
      INPUT_LOAD='(-0.01,0.01)';
    'SCL|||SMBCLK':
      PIN_NUMBER='(5)';
      INPUT_LOAD='(-0.01,0.01)';
    'SDA||SMBDAT':
      PIN_NUMBER='(4)';
      BIDIRECTIONAL='TRUE';
      INPUT_LOAD='(-0.01,0.01)';
      OUTPUT_LOAD='(1.0,-1.0)';
    'VBUS':
      PIN_NUMBER='(11)';
      PINUSE='POWER';
      NO_LOAD_CHECK='Both';
      NO_IO_CHECK='Both';
      NO_ASSERT_CHECK='TRUE';
      NO_DIR_CHECK='TRUE';
      ALLOW_CONNECT='TRUE';
    'VINP':
      PIN_NUMBER='(13)';
      INPUT_LOAD='(-0.01,0.01)';
    'VINM':
      PIN_NUMBER='(12)';
      INPUT_LOAD='(-0.01,0.01)';
    'EXT_CLK||INT':
      PIN_NUMBER='(3)';
      BIDIRECTIONAL='TRUE';
      INPUT_LOAD='(-0.01,0.01)';
      OUTPUT_LOAD='(1.0,-1.0)';
    'NC0':
      PIN_NUMBER='(6)';
      OUTPUT_TYPE='(TS,TS)';
      INPUT_LOAD='(-0.01,0.01)';
      OUTPUT_LOAD='(1.0,-1.0)';
    'NC1':
      PIN_NUMBER='(7)';
      OUTPUT_TYPE='(TS,TS)';
      INPUT_LOAD='(-0.01,0.01)';
      OUTPUT_LOAD='(1.0,-1.0)';
    'NC2':
      PIN_NUMBER='(8)';
      OUTPUT_TYPE='(TS,TS)';
      INPUT_LOAD='(-0.01,0.01)';
      OUTPUT_LOAD='(1.0,-1.0)';
    'NC3':
      PIN_NUMBER='(14)';
      OUTPUT_TYPE='(TS,TS)';
      INPUT_LOAD='(-0.01,0.01)';
      OUTPUT_LOAD='(1.0,-1.0)';
    'NC4':
      PIN_NUMBER='(15)';
      OUTPUT_TYPE='(TS,TS)';
      INPUT_LOAD='(-0.01,0.01)';
      OUTPUT_LOAD='(1.0,-1.0)';
    'NC5':
      PIN_NUMBER='(16)';
      OUTPUT_TYPE='(TS,TS)';
      INPUT_LOAD='(-0.01,0.01)';
      OUTPUT_LOAD='(1.0,-1.0)';
    'GND':
      PIN_NUMBER='(10)';
      PINUSE='POWER';
      NO_LOAD_CHECK='Both';
      NO_IO_CHECK='Both';
      NO_ASSERT_CHECK='TRUE';
      NO_DIR_CHECK='TRUE';
      ALLOW_CONNECT='TRUE';
    'TH_GND':
      PIN_NUMBER='(TH)';
      PINUSE='POWER';
      NO_LOAD_CHECK='Both';
      NO_IO_CHECK='Both';
      NO_ASSERT_CHECK='TRUE';
      NO_DIR_CHECK='TRUE';
      ALLOW_CONNECT='TRUE';
  end_pin;
  body
    PART_NAME='ISL28022FRZT';
    BODY_NAME='ISL28022FRZT';
    PHYS_DES_PREFIX='U';
    CLASS='IC';
  end_body;
end_primitive;

END.
